# S9S_MB_2U (Grand Teton) — schematic netlist excerpt (pin names and nets, part order shuffled) for the footprints in the layout excerpt that follows; sources: Cadence DE-HDL packaged netlist, KiCad conversion of 03242023_DA0F0TMBIJ0_F0T_Motherboard_J_brd_V01_OCP.brd

R4298  Q_RES  100 1% CHIP  pkg 0402LF  page 124 : A = PWRGD_DRAMPWRGD_CPU0_GH_LVC1_R2 ; B = PWRGD_DRAMPWRGD_CPU0_GH_LVC1_R
R3214  Q_RES  0 5% EMPTY  pkg 0402LF  page 160 : A = NCSI_BMC_TXD0_R1 ; B = RMII_BMC_OCP_TXD_0

(kicad_pcb
	(version 20260206)
	(generator "pcbnew")
	(generator_version "10.0")
	(general
		(thickness 1.6)
		(legacy_teardrops no)
	)
	(paper "A4")
	(title_block
		(title "03242023_DA0F0TMBIJ0_F0T_Motherboard_J_brd_V01_OCP.brd")
		(comment 1 "Grand Teton / footprints 4440-4441 of 6105")
	)
	(layers
		(0 "F.Cu" signal "TOP")
		(4 "In1.Cu" signal "GND")
		(6 "In2.Cu" signal "IN1")
		(8 "In3.Cu" signal "GND1")
		(10 "In4.Cu" signal "IN2")
		(12 "In5.Cu" signal "GND2")
		(14 "In6.Cu" signal "IN3")
		(16 "In7.Cu" signal "GND3")
		(18 "In8.Cu" signal "VCC")
		(20 "In9.Cu" signal "VCC1")
		(22 "In10.Cu" signal "GND4")
		(24 "In11.Cu" signal "IN4")
		(26 "In12.Cu" signal "GND5")
		(28 "In13.Cu" signal "IN5")
		(30 "In14.Cu" signal "GND6")
		(32 "In15.Cu" signal "IN6")
		(34 "In16.Cu" signal "GND7")
		(2 "B.Cu" signal "BOTTOM")
		(9 "F.Adhes" user "F.Adhesive")
		(11 "B.Adhes" user "B.Adhesive")
		(13 "F.Paste" user "Package Geometry/Pastemask Top")
		(15 "B.Paste" user "Package Geometry/Pastemask Bottom")
		(5 "F.SilkS" user "Ref Des/Silkscreen Top")
		(7 "B.SilkS" user "Ref Des/Silkscreen Bottom")
		(1 "F.Mask" user "Board Geometry/Soldermask Top")
		(3 "B.Mask" user "Board Geometry/Soldermask Bottom")
		(17 "Dwgs.User" user "User.Drawings")
		(19 "Cmts.User" user "User.Comments")
		(21 "Eco1.User" user "User.Eco1")
		(23 "Eco2.User" user "User.Eco2")
		(25 "Edge.Cuts" user "Board Geometry/Outline")
		(27 "Margin" user)
		(31 "F.CrtYd" user "Package Geometry/Place Bound Top")
		(29 "B.CrtYd" user "Package Geometry/Place Bound Bottom")
		(35 "F.Fab" user "Ref Des/Assembly Top")
		(33 "B.Fab" user "Ref Des/Assembly Bottom")
	)
	(footprint ""
		(layer "B.Cu")
		(at 206.162656 -70.31228 180)
		(property "Reference" "R3214"
			(at 0 0 0)
			(layer "B.SilkS")
			(hide yes)
			(effects
				(font
					(size 1.27 1.27)
				)
				(justify mirror)
			)
		)
		(property "Value" ""
			(at 0 0 0)
			(layer "B.Fab")
			(effects
				(font
					(size 1.27 1.27)
				)
				(justify mirror)
			)
		)
		(duplicate_pad_numbers_are_jumpers no)
		(fp_line
			(start 0.7874 0.4064)
			(end 0.7874 -0.4064)
			(stroke
				(width 0.1524)
				(type default)
			)
			(layer "B.SilkS")
		)
		(fp_line
			(start 0.7874 -0.4064)
			(end -0.7874 -0.4064)
			(stroke
				(width 0.1524)
				(type default)
			)
			(layer "B.SilkS")
		)
		(fp_line
			(start -0.7874 0.4064)
			(end 0.7874 0.4064)
			(stroke
				(width 0.1524)
				(type default)
			)
			(layer "B.SilkS")
		)
		(fp_line
			(start -0.7874 -0.4064)
			(end -0.7874 0.4064)
			(stroke
				(width 0.1524)
				(type default)
			)
			(layer "B.SilkS")
		)
		(fp_line
			(start 0.67945 0.3048)
			(end 0.67945 -0.305054)
			(stroke
				(width 0.1)
				(type default)
			)
			(layer "B.Fab")
		)
		(fp_line
			(start 0.67945 -0.305054)
			(end 0.12065 -0.305054)
			(stroke
				(width 0.1)
				(type default)
			)
			(layer "B.Fab")
		)
		(fp_line
			(start 0.12065 0.3048)
			(end 0.67945 0.3048)
			(stroke
				(width 0.1)
				(type default)
			)
			(layer "B.Fab")
		)
		(fp_line
			(start 0.12065 0.2794)
			(end 0.12065 0.3048)
			(stroke
				(width 0.1)
				(type default)
			)
			(layer "B.Fab")
		)
		(fp_line
			(start 0.12065 -0.2794)
			(end -0.12065 -0.2794)
			(stroke
				(width 0.1)
				(type default)
			)
			(layer "B.Fab")
		)
		(fp_line
			(start 0.12065 -0.305054)
			(end 0.12065 -0.2794)
			(stroke
				(width 0.1)
				(type default)
			)
			(layer "B.Fab")
		)
		(fp_line
			(start -0.120396 0.3048)
			(end -0.120396 0.2794)
			(stroke
				(width 0.1)
				(type default)
			)
			(layer "B.Fab")
		)
		(fp_line
			(start -0.120396 0.2794)
			(end 0.12065 0.2794)
			(stroke
				(width 0.1)
				(type default)
			)
			(layer "B.Fab")
		)
		(fp_line
			(start -0.12065 -0.2794)
			(end -0.12065 -0.3048)
			(stroke
				(width 0.1)
				(type default)
			)
			(layer "B.Fab")
		)
		(fp_line
			(start -0.12065 -0.3048)
			(end -0.67945 -0.3048)
			(stroke
				(width 0.1)
				(type default)
			)
			(layer "B.Fab")
		)
		(fp_line
			(start -0.67945 0.3048)
			(end -0.120396 0.3048)
			(stroke
				(width 0.1)
				(type default)
			)
			(layer "B.Fab")
		)
		(fp_line
			(start -0.67945 -0.3048)
			(end -0.67945 0.3048)
			(stroke
				(width 0.1)
				(type default)
			)
			(layer "B.Fab")
		)
		(pad "1" smd circle
			(at 0.40005 0)
			(size 0 0)
			(layers "B.Cu" "B.Mask" "B.Paste")
			(net "NCSI_BMC_TXD0_R1")
		)
		(pad "2" smd circle
			(at -0.40005 0)
			(size 0 0)
			(layers "B.Cu" "B.Mask" "B.Paste")
			(net "RMII_BMC_OCP_TXD_0")
		)
	)
	(footprint ""
		(layer "B.Cu")
		(at 402.336 -190.845948 -90)
		(property "Reference" "R4298"
			(at 0 0 90)
			(layer "B.SilkS")
			(hide yes)
			(effects
				(font
					(size 1.27 1.27)
				)
				(justify mirror)
			)
		)
		(property "Value" ""
			(at 0 0 90)
			(layer "B.Fab")
			(effects
				(font
					(size 1.27 1.27)
				)
				(justify mirror)
			)
		)
		(duplicate_pad_numbers_are_jumpers no)
		(fp_line
			(start -0.7874 0.4064)
			(end 0.7874 0.4064)
			(stroke
				(width 0.1524)
				(type default)
			)
			(layer "B.SilkS")
		)
		(fp_line
			(start 0.7874 0.4064)
			(end 0.7874 -0.4064)
			(stroke
				(width 0.1524)
				(type default)
			)
			(layer "B.SilkS")
		)
		(fp_line
			(start -0.7874 -0.4064)
			(end -0.7874 0.4064)
			(stroke
				(width 0.1524)
				(type default)
			)
			(layer "B.SilkS")
		)
		(fp_line
			(start 0.7874 -0.4064)
			(end -0.7874 -0.4064)
			(stroke
				(width 0.1524)
				(type default)
			)
			(layer "B.SilkS")
		)
		(fp_line
			(start -0.67945 0.3048)
			(end -0.120396 0.3048)
			(stroke
				(width 0.1)
				(type default)
			)
			(layer "B.Fab")
		)
		(fp_line
			(start -0.120396 0.3048)
			(end -0.120396 0.2794)
			(stroke
				(width 0.1)
				(type default)
			)
			(layer "B.Fab")
		)
		(fp_line
			(start 0.12065 0.3048)
			(end 0.67945 0.3048)
			(stroke
				(width 0.1)
				(type default)
			)
			(layer "B.Fab")
		)
		(fp_line
			(start 0.67945 0.3048)
			(end 0.67945 -0.305054)
			(stroke
				(width 0.1)
				(type default)
			)
			(layer "B.Fab")
		)
		(fp_line
			(start -0.120396 0.2794)
			(end 0.12065 0.2794)
			(stroke
				(width 0.1)
				(type default)
			)
			(layer "B.Fab")
		)
		(fp_line
			(start 0.12065 0.2794)
			(end 0.12065 0.3048)
			(stroke
				(width 0.1)
				(type default)
			)
			(layer "B.Fab")
		)
		(fp_line
			(start -0.12065 -0.2794)
			(end -0.12065 -0.3048)
			(stroke
				(width 0.1)
				(type default)
			)
			(layer "B.Fab")
		)
		(fp_line
			(start 0.12065 -0.2794)
			(end -0.12065 -0.2794)
			(stroke
				(width 0.1)
				(type default)
			)
			(layer "B.Fab")
		)
		(fp_line
			(start -0.67945 -0.3048)
			(end -0.67945 0.3048)
			(stroke
				(width 0.1)
				(type default)
			)
			(layer "B.Fab")
		)
		(fp_line
			(start -0.12065 -0.3048)
			(end -0.67945 -0.3048)
			(stroke
				(width 0.1)
				(type default)
			)
			(layer "B.Fab")
		)
		(fp_line
			(start 0.12065 -0.305054)
			(end 0.12065 -0.2794)
			(stroke
				(width 0.1)
				(type default)
			)
			(layer "B.Fab")
		)
		(fp_line
			(start 0.67945 -0.305054)
			(end 0.12065 -0.305054)
			(stroke
				(width 0.1)
				(type default)
			)
			(layer "B.Fab")
		)
		(pad "1" smd circle
			(at 0.40005 0 90)
			(size 0 0)
			(layers "B.Cu" "B.Mask" "B.Paste")
			(net "PWRGD_DRAMPWRGD_CPU0_GH_LVC1_R2")
		)
		(pad "2" smd circle
			(at -0.40005 0 90)
			(size 0 0)
			(layers "B.Cu" "B.Mask" "B.Paste")
			(net "PWRGD_DRAMPWRGD_CPU0_GH_LVC1_R")
		)
	)
)
